(kicad_pcb
	(version 20260206)
	(generator "pcbnew")
	(generator_version "10.0")
	(general
		(thickness 1.6)
		(legacy_teardrops no)
	)
	(paper "A4")
	(title_block
		(title "01162023_DA0F0TEBIF0_F0T_Expander_BD_F_brd_V02_OCP.brd")
		(comment 1 "Grand Teton / footprints 5099-5105 of 9728")
	)
	(layers
		(0 "F.Cu" signal "TOP")
		(4 "In1.Cu" signal "GND")
		(6 "In2.Cu" signal "VCC")
		(8 "In3.Cu" signal "VCC1")
		(10 "In4.Cu" signal "GND1")
		(12 "In5.Cu" signal "IN1")
		(14 "In6.Cu" signal "GND2")
		(16 "In7.Cu" signal "IN2")
		(18 "In8.Cu" signal "GND3")
		(20 "In9.Cu" signal "IN3")
		(22 "In10.Cu" signal "GND4")
		(24 "In11.Cu" signal "IN4")
		(26 "In12.Cu" signal "GND5")
		(28 "In13.Cu" signal "IN5")
		(30 "In14.Cu" signal "GND6")
		(32 "In15.Cu" signal "IN6")
		(34 "In16.Cu" signal "GND7")
		(2 "B.Cu" signal "BOTTOM")
		(9 "F.Adhes" user "F.Adhesive")
		(11 "B.Adhes" user "B.Adhesive")
		(13 "F.Paste" user "Package Geometry/Pastemask Top")
		(15 "B.Paste" user "Package Geometry/Pastemask Bottom")
		(5 "F.SilkS" user "Ref Des/Silkscreen Top")
		(7 "B.SilkS" user "Ref Des/Silkscreen Bottom")
		(1 "F.Mask" user "Board Geometry/Soldermask Top")
		(3 "B.Mask" user "Board Geometry/Soldermask Bottom")
		(17 "Dwgs.User" user "User.Drawings")
		(19 "Cmts.User" user "User.Comments")
		(21 "Eco1.User" user "User.Eco1")
		(23 "Eco2.User" user "User.Eco2")
		(25 "Edge.Cuts" user "Board Geometry/Outline")
		(27 "Margin" user)
		(31 "F.CrtYd" user "Package Geometry/Place Bound Top")
		(29 "B.CrtYd" user "Package Geometry/Place Bound Bottom")
		(35 "F.Fab" user "Ref Des/Assembly Top")
		(33 "B.Fab" user "Ref Des/Assembly Bottom")
	)
	(footprint ""
		(layer "F.Cu")
		(at 459.324202 -246.80164 90)
		(property "Reference" "R6585"
			(at 0 0 90)
			(layer "F.SilkS")
			(hide yes)
			(effects
				(font
					(size 1.27 1.27)
				)
			)
		)
		(property "Value" ""
			(at 0 0 90)
			(layer "F.Fab")
			(effects
				(font
					(size 1.27 1.27)
				)
			)
		)
		(duplicate_pad_numbers_are_jumpers no)
		(fp_line
			(start 0.7874 -0.4064)
			(end 0.7874 0.4064)
			(stroke
				(width 0.1524)
				(type default)
			)
			(layer "F.SilkS")
		)
		(fp_line
			(start -0.7874 -0.4064)
			(end 0.7874 -0.4064)
			(stroke
				(width 0.1524)
				(type default)
			)
			(layer "F.SilkS")
		)
		(fp_line
			(start 0.7874 0.4064)
			(end -0.7874 0.4064)
			(stroke
				(width 0.1524)
				(type default)
			)
			(layer "F.SilkS")
		)
		(fp_line
			(start -0.7874 0.4064)
			(end -0.7874 -0.4064)
			(stroke
				(width 0.1524)
				(type default)
			)
			(layer "F.SilkS")
		)
		(fp_line
			(start -0.12065 -0.305054)
			(end -0.12065 -0.2794)
			(stroke
				(width 0.1)
				(type default)
			)
			(layer "F.Fab")
		)
		(fp_line
			(start -0.67945 -0.305054)
			(end -0.12065 -0.305054)
			(stroke
				(width 0.1)
				(type default)
			)
			(layer "F.Fab")
		)
		(fp_line
			(start 0.67945 -0.3048)
			(end 0.67945 0.3048)
			(stroke
				(width 0.1)
				(type default)
			)
			(layer "F.Fab")
		)
		(fp_line
			(start 0.12065 -0.3048)
			(end 0.67945 -0.3048)
			(stroke
				(width 0.1)
				(type default)
			)
			(layer "F.Fab")
		)
		(fp_line
			(start 0.12065 -0.2794)
			(end 0.12065 -0.3048)
			(stroke
				(width 0.1)
				(type default)
			)
			(layer "F.Fab")
		)
		(fp_line
			(start -0.12065 -0.2794)
			(end 0.12065 -0.2794)
			(stroke
				(width 0.1)
				(type default)
			)
			(layer "F.Fab")
		)
		(fp_line
			(start 0.120396 0.2794)
			(end -0.12065 0.2794)
			(stroke
				(width 0.1)
				(type default)
			)
			(layer "F.Fab")
		)
		(fp_line
			(start -0.12065 0.2794)
			(end -0.12065 0.3048)
			(stroke
				(width 0.1)
				(type default)
			)
			(layer "F.Fab")
		)
		(fp_line
			(start 0.67945 0.3048)
			(end 0.120396 0.3048)
			(stroke
				(width 0.1)
				(type default)
			)
			(layer "F.Fab")
		)
		(fp_line
			(start 0.120396 0.3048)
			(end 0.120396 0.2794)
			(stroke
				(width 0.1)
				(type default)
			)
			(layer "F.Fab")
		)
		(fp_line
			(start -0.12065 0.3048)
			(end -0.67945 0.3048)
			(stroke
				(width 0.1)
				(type default)
			)
			(layer "F.Fab")
		)
		(fp_line
			(start -0.67945 0.3048)
			(end -0.67945 -0.305054)
			(stroke
				(width 0.1)
				(type default)
			)
			(layer "F.Fab")
		)
		(pad "1" smd circle
			(at -0.40005 0 90)
			(size 0 0)
			(layers "F.Cu" "F.Mask" "F.Paste")
			(net "P1V8_PLL0_PEX3")
		)
		(pad "2" smd circle
			(at 0.40005 0 90)
			(size 0 0)
			(layers "F.Cu" "F.Mask" "F.Paste")
			(net "P1V8_PLL_PEX3_ADJ")
		)
	)
	(footprint ""
		(layer "F.Cu")
		(at 225.39706 -278.675846 90)
		(property "Reference" "C629"
			(at 0 0 90)
			(layer "F.SilkS")
			(hide yes)
			(effects
				(font
					(size 1.27 1.27)
				)
			)
		)
		(property "Value" ""
			(at 0 0 90)
			(layer "F.Fab")
			(effects
				(font
					(size 1.27 1.27)
				)
			)
		)
		(duplicate_pad_numbers_are_jumpers no)
		(fp_line
			(start 0.7874 -0.4064)
			(end 0.7874 0.4064)
			(stroke
				(width 0.1524)
				(type default)
			)
			(layer "F.SilkS")
		)
		(fp_line
			(start -0.7874 -0.4064)
			(end 0.7874 -0.4064)
			(stroke
				(width 0.1524)
				(type default)
			)
			(layer "F.SilkS")
		)
		(fp_line
			(start 0.7874 0.4064)
			(end -0.7874 0.4064)
			(stroke
				(width 0.1524)
				(type default)
			)
			(layer "F.SilkS")
		)
		(fp_line
			(start -0.7874 0.4064)
			(end -0.7874 -0.4064)
			(stroke
				(width 0.1524)
				(type default)
			)
			(layer "F.SilkS")
		)
		(fp_line
			(start -0.12065 -0.305054)
			(end -0.12065 -0.2794)
			(stroke
				(width 0.1)
				(type default)
			)
			(layer "F.Fab")
		)
		(fp_line
			(start -0.67945 -0.305054)
			(end -0.12065 -0.305054)
			(stroke
				(width 0.1)
				(type default)
			)
			(layer "F.Fab")
		)
		(fp_line
			(start 0.67945 -0.3048)
			(end 0.67945 0.3048)
			(stroke
				(width 0.1)
				(type default)
			)
			(layer "F.Fab")
		)
		(fp_line
			(start 0.12065 -0.3048)
			(end 0.67945 -0.3048)
			(stroke
				(width 0.1)
				(type default)
			)
			(layer "F.Fab")
		)
		(fp_line
			(start 0.12065 -0.2794)
			(end 0.12065 -0.3048)
			(stroke
				(width 0.1)
				(type default)
			)
			(layer "F.Fab")
		)
		(fp_line
			(start -0.12065 -0.2794)
			(end 0.12065 -0.2794)
			(stroke
				(width 0.1)
				(type default)
			)
			(layer "F.Fab")
		)
		(fp_line
			(start 0.120396 0.2794)
			(end -0.12065 0.2794)
			(stroke
				(width 0.1)
				(type default)
			)
			(layer "F.Fab")
		)
		(fp_line
			(start -0.12065 0.2794)
			(end -0.12065 0.3048)
			(stroke
				(width 0.1)
				(type default)
			)
			(layer "F.Fab")
		)
		(fp_line
			(start 0.67945 0.3048)
			(end 0.120396 0.3048)
			(stroke
				(width 0.1)
				(type default)
			)
			(layer "F.Fab")
		)
		(fp_line
			(start 0.120396 0.3048)
			(end 0.120396 0.2794)
			(stroke
				(width 0.1)
				(type default)
			)
			(layer "F.Fab")
		)
		(fp_line
			(start -0.12065 0.3048)
			(end -0.67945 0.3048)
			(stroke
				(width 0.1)
				(type default)
			)
			(layer "F.Fab")
		)
		(fp_line
			(start -0.67945 0.3048)
			(end -0.67945 -0.305054)
			(stroke
				(width 0.1)
				(type default)
			)
			(layer "F.Fab")
		)
		(pad "1" smd circle
			(at -0.40005 0 90)
			(size 0 0)
			(layers "F.Cu" "F.Mask" "F.Paste")
			(net "P1V25_PEX1_R")
		)
		(pad "2" smd circle
			(at 0.40005 0 90)
			(size 0 0)
			(layers "F.Cu" "F.Mask" "F.Paste")
			(net "GND")
		)
	)
	(footprint ""
		(layer "F.Cu")
		(at 412.378652 -350.098614 90)
		(property "Reference" "C822"
			(at 0 0 90)
			(layer "F.SilkS")
			(hide yes)
			(effects
				(font
					(size 1.27 1.27)
				)
			)
		)
		(property "Value" ""
			(at 0 0 90)
			(layer "F.Fab")
			(effects
				(font
					(size 1.27 1.27)
				)
			)
		)
		(duplicate_pad_numbers_are_jumpers no)
		(fp_line
			(start 0.299974 -0.150114)
			(end 0.299974 0.150114)
			(stroke
				(width 0.1)
				(type default)
			)
			(layer "F.Fab")
		)
		(fp_line
			(start -0.299974 -0.150114)
			(end 0.299974 -0.150114)
			(stroke
				(width 0.1)
				(type default)
			)
			(layer "F.Fab")
		)
		(fp_line
			(start 0.299974 0.150114)
			(end -0.299974 0.150114)
			(stroke
				(width 0.1)
				(type default)
			)
			(layer "F.Fab")
		)
		(fp_line
			(start -0.299974 0.150114)
			(end -0.299974 -0.150114)
			(stroke
				(width 0.1)
				(type default)
			)
			(layer "F.Fab")
		)
		(pad "1" smd rect
			(at -0.2667 0 90)
			(size 0.3048 0.381)
			(layers "F.Cu" "F.Mask" "F.Paste")
			(net "P5E_PEX3_STN7_TX_DP<113>")
		)
		(pad "2" smd rect
			(at 0.2667 0 90)
			(size 0.3048 0.381)
			(layers "F.Cu" "F.Mask" "F.Paste")
			(net "P5E_PEX3_STN7_TX_C_DP<113>")
		)
	)
	(footprint ""
		(layer "F.Cu")
		(at 420.73449 -34.546286 180)
		(property "Reference" "C714"
			(at 0 0 180)
			(layer "F.SilkS")
			(hide yes)
			(effects
				(font
					(size 1.27 1.27)
				)
			)
		)
		(property "Value" ""
			(at 0 0 180)
			(layer "F.Fab")
			(effects
				(font
					(size 1.27 1.27)
				)
			)
		)
		(duplicate_pad_numbers_are_jumpers no)
		(fp_line
			(start 0.299974 0.150114)
			(end -0.299974 0.150114)
			(stroke
				(width 0.1)
				(type default)
			)
			(layer "F.Fab")
		)
		(fp_line
			(start 0.299974 -0.150114)
			(end 0.299974 0.150114)
			(stroke
				(width 0.1)
				(type default)
			)
			(layer "F.Fab")
		)
		(fp_line
			(start -0.299974 0.150114)
			(end -0.299974 -0.150114)
			(stroke
				(width 0.1)
				(type default)
			)
			(layer "F.Fab")
		)
		(fp_line
			(start -0.299974 -0.150114)
			(end 0.299974 -0.150114)
			(stroke
				(width 0.1)
				(type default)
			)
			(layer "F.Fab")
		)
		(pad "1" smd rect
			(at -0.2667 0 180)
			(size 0.3048 0.381)
			(layers "F.Cu" "F.Mask" "F.Paste")
			(net "P5E_PEX3_STN2_TX_DP<39>")
		)
		(pad "2" smd rect
			(at 0.2667 0 180)
			(size 0.3048 0.381)
			(layers "F.Cu" "F.Mask" "F.Paste")
			(net "P5E_PEX3_STN2_TX_C_DP<39>")
		)
	)
	(footprint ""
		(layer "F.Cu")
		(at 92.28328 -113.628678)
		(property "Reference" "PC659"
			(at 0 0 0)
			(layer "F.SilkS")
			(hide yes)
			(effects
				(font
					(size 1.27 1.27)
				)
			)
		)
		(property "Value" ""
			(at 0 0 0)
			(layer "F.Fab")
			(effects
				(font
					(size 1.27 1.27)
				)
			)
		)
		(duplicate_pad_numbers_are_jumpers no)
		(fp_line
			(start -0.7874 -0.4064)
			(end 0.7874 -0.4064)
			(stroke
				(width 0.1524)
				(type default)
			)
			(layer "F.SilkS")
		)
		(fp_line
			(start -0.7874 0.4064)
			(end -0.7874 -0.4064)
			(stroke
				(width 0.1524)
				(type default)
			)
			(layer "F.SilkS")
		)
		(fp_line
			(start 0.7874 -0.4064)
			(end 0.7874 0.4064)
			(stroke
				(width 0.1524)
				(type default)
			)
			(layer "F.SilkS")
		)
		(fp_line
			(start 0.7874 0.4064)
			(end -0.7874 0.4064)
			(stroke
				(width 0.1524)
				(type default)
			)
			(layer "F.SilkS")
		)
		(fp_line
			(start -0.67945 -0.305054)
			(end -0.12065 -0.305054)
			(stroke
				(width 0.1)
				(type default)
			)
			(layer "F.Fab")
		)
		(fp_line
			(start -0.67945 0.3048)
			(end -0.67945 -0.305054)
			(stroke
				(width 0.1)
				(type default)
			)
			(layer "F.Fab")
		)
		(fp_line
			(start -0.12065 -0.305054)
			(end -0.12065 -0.2794)
			(stroke
				(width 0.1)
				(type default)
			)
			(layer "F.Fab")
		)
		(fp_line
			(start -0.12065 -0.2794)
			(end 0.12065 -0.2794)
			(stroke
				(width 0.1)
				(type default)
			)
			(layer "F.Fab")
		)
		(fp_line
			(start -0.12065 0.2794)
			(end -0.12065 0.3048)
			(stroke
				(width 0.1)
				(type default)
			)
			(layer "F.Fab")
		)
		(fp_line
			(start -0.12065 0.3048)
			(end -0.67945 0.3048)
			(stroke
				(width 0.1)
				(type default)
			)
			(layer "F.Fab")
		)
		(fp_line
			(start 0.120396 0.2794)
			(end -0.12065 0.2794)
			(stroke
				(width 0.1)
				(type default)
			)
			(layer "F.Fab")
		)
		(fp_line
			(start 0.120396 0.3048)
			(end 0.120396 0.2794)
			(stroke
				(width 0.1)
				(type default)
			)
			(layer "F.Fab")
		)
		(fp_line
			(start 0.12065 -0.3048)
			(end 0.67945 -0.3048)
			(stroke
				(width 0.1)
				(type default)
			)
			(layer "F.Fab")
		)
		(fp_line
			(start 0.12065 -0.2794)
			(end 0.12065 -0.3048)
			(stroke
				(width 0.1)
				(type default)
			)
			(layer "F.Fab")
		)
		(fp_line
			(start 0.67945 -0.3048)
			(end 0.67945 0.3048)
			(stroke
				(width 0.1)
				(type default)
			)
			(layer "F.Fab")
		)
		(fp_line
			(start 0.67945 0.3048)
			(end 0.120396 0.3048)
			(stroke
				(width 0.1)
				(type default)
			)
			(layer "F.Fab")
		)
		(pad "1" smd circle
			(at -0.40005 0)
			(size 0 0)
			(layers "F.Cu" "F.Mask" "F.Paste")
			(net "P3V3_AUX")
		)
		(pad "2" smd circle
			(at 0.40005 0)
			(size 0 0)
			(layers "F.Cu" "F.Mask" "F.Paste")
			(net "GND")
		)
	)
	(footprint ""
		(layer "F.Cu")
		(at 291.194998 -96.702372 180)
		(property "Reference" "R302"
			(at 0 0 180)
			(layer "F.SilkS")
			(hide yes)
			(effects
				(font
					(size 1.27 1.27)
				)
			)
		)
		(property "Value" ""
			(at 0 0 180)
			(layer "F.Fab")
			(effects
				(font
					(size 1.27 1.27)
				)
			)
		)
		(duplicate_pad_numbers_are_jumpers no)
		(fp_line
			(start 0.7874 0.4064)
			(end -0.7874 0.4064)
			(stroke
				(width 0.1524)
				(type default)
			)
			(layer "F.SilkS")
		)
		(fp_line
			(start 0.7874 -0.4064)
			(end 0.7874 0.4064)
			(stroke
				(width 0.1524)
				(type default)
			)
			(layer "F.SilkS")
		)
		(fp_line
			(start -0.7874 0.4064)
			(end -0.7874 -0.4064)
			(stroke
				(width 0.1524)
				(type default)
			)
			(layer "F.SilkS")
		)
		(fp_line
			(start -0.7874 -0.4064)
			(end 0.7874 -0.4064)
			(stroke
				(width 0.1524)
				(type default)
			)
			(layer "F.SilkS")
		)
		(fp_line
			(start 0.67945 0.3048)
			(end 0.120396 0.3048)
			(stroke
				(width 0.1)
				(type default)
			)
			(layer "F.Fab")
		)
		(fp_line
			(start 0.67945 -0.3048)
			(end 0.67945 0.3048)
			(stroke
				(width 0.1)
				(type default)
			)
			(layer "F.Fab")
		)
		(fp_line
			(start 0.12065 -0.2794)
			(end 0.12065 -0.3048)
			(stroke
				(width 0.1)
				(type default)
			)
			(layer "F.Fab")
		)
		(fp_line
			(start 0.12065 -0.3048)
			(end 0.67945 -0.3048)
			(stroke
				(width 0.1)
				(type default)
			)
			(layer "F.Fab")
		)
		(fp_line
			(start 0.120396 0.3048)
			(end 0.120396 0.2794)
			(stroke
				(width 0.1)
				(type default)
			)
			(layer "F.Fab")
		)
		(fp_line
			(start 0.120396 0.2794)
			(end -0.12065 0.2794)
			(stroke
				(width 0.1)
				(type default)
			)
			(layer "F.Fab")
		)
		(fp_line
			(start -0.12065 0.3048)
			(end -0.67945 0.3048)
			(stroke
				(width 0.1)
				(type default)
			)
			(layer "F.Fab")
		)
		(fp_line
			(start -0.12065 0.2794)
			(end -0.12065 0.3048)
			(stroke
				(width 0.1)
				(type default)
			)
			(layer "F.Fab")
		)
		(fp_line
			(start -0.12065 -0.2794)
			(end 0.12065 -0.2794)
			(stroke
				(width 0.1)
				(type default)
			)
			(layer "F.Fab")
		)
		(fp_line
			(start -0.12065 -0.305054)
			(end -0.12065 -0.2794)
			(stroke
				(width 0.1)
				(type default)
			)
			(layer "F.Fab")
		)
		(fp_line
			(start -0.67945 0.3048)
			(end -0.67945 -0.305054)
			(stroke
				(width 0.1)
				(type default)
			)
			(layer "F.Fab")
		)
		(fp_line
			(start -0.67945 -0.305054)
			(end -0.12065 -0.305054)
			(stroke
				(width 0.1)
				(type default)
			)
			(layer "F.Fab")
		)
		(pad "1" smd circle
			(at -0.40005 0 180)
			(size 0 0)
			(layers "F.Cu" "F.Mask" "F.Paste")
			(net "RST_NIC5_PERST2_R_N")
		)
		(pad "2" smd circle
			(at 0.40005 0 180)
			(size 0 0)
			(layers "F.Cu" "F.Mask" "F.Paste")
			(net "RST_HP_NIC5_BUF_N")
		)
	)
	(footprint ""
		(layer "F.Cu")
		(at 91.287092 -297.27398 180)
		(property "Reference" "R3874"
			(at 0 0 180)
			(layer "F.SilkS")
			(hide yes)
			(effects
				(font
					(size 1.27 1.27)
				)
			)
		)
		(property "Value" ""
			(at 0 0 180)
			(layer "F.Fab")
			(effects
				(font
					(size 1.27 1.27)
				)
			)
		)
		(duplicate_pad_numbers_are_jumpers no)
		(fp_line
			(start 0.7874 0.4064)
			(end -0.7874 0.4064)
			(stroke
				(width 0.1524)
				(type default)
			)
			(layer "F.SilkS")
		)
		(fp_line
			(start 0.7874 -0.4064)
			(end 0.7874 0.4064)
			(stroke
				(width 0.1524)
				(type default)
			)
			(layer "F.SilkS")
		)
		(fp_line
			(start -0.7874 0.4064)
			(end -0.7874 -0.4064)
			(stroke
				(width 0.1524)
				(type default)
			)
			(layer "F.SilkS")
		)
		(fp_line
			(start -0.7874 -0.4064)
			(end 0.7874 -0.4064)
			(stroke
				(width 0.1524)
				(type default)
			)
			(layer "F.SilkS")
		)
		(fp_line
			(start 0.67945 0.3048)
			(end 0.120396 0.3048)
			(stroke
				(width 0.1)
				(type default)
			)
			(layer "F.Fab")
		)
		(fp_line
			(start 0.67945 -0.3048)
			(end 0.67945 0.3048)
			(stroke
				(width 0.1)
				(type default)
			)
			(layer "F.Fab")
		)
		(fp_line
			(start 0.12065 -0.2794)
			(end 0.12065 -0.3048)
			(stroke
				(width 0.1)
				(type default)
			)
			(layer "F.Fab")
		)
		(fp_line
			(start 0.12065 -0.3048)
			(end 0.67945 -0.3048)
			(stroke
				(width 0.1)
				(type default)
			)
			(layer "F.Fab")
		)
		(fp_line
			(start 0.120396 0.3048)
			(end 0.120396 0.2794)
			(stroke
				(width 0.1)
				(type default)
			)
			(layer "F.Fab")
		)
		(fp_line
			(start 0.120396 0.2794)
			(end -0.12065 0.2794)
			(stroke
				(width 0.1)
				(type default)
			)
			(layer "F.Fab")
		)
		(fp_line
			(start -0.12065 0.3048)
			(end -0.67945 0.3048)
			(stroke
				(width 0.1)
				(type default)
			)
			(layer "F.Fab")
		)
		(fp_line
			(start -0.12065 0.2794)
			(end -0.12065 0.3048)
			(stroke
				(width 0.1)
				(type default)
			)
			(layer "F.Fab")
		)
		(fp_line
			(start -0.12065 -0.2794)
			(end 0.12065 -0.2794)
			(stroke
				(width 0.1)
				(type default)
			)
			(layer "F.Fab")
		)
		(fp_line
			(start -0.12065 -0.305054)
			(end -0.12065 -0.2794)
			(stroke
				(width 0.1)
				(type default)
			)
			(layer "F.Fab")
		)
		(fp_line
			(start -0.67945 0.3048)
			(end -0.67945 -0.305054)
			(stroke
				(width 0.1)
				(type default)
			)
			(layer "F.Fab")
		)
		(fp_line
			(start -0.67945 -0.305054)
			(end -0.12065 -0.305054)
			(stroke
				(width 0.1)
				(type default)
			)
			(layer "F.Fab")
		)
		(pad "1" smd circle
			(at -0.40005 0 180)
			(size 0 0)
			(layers "F.Cu" "F.Mask" "F.Paste")
			(net "SMB_PEX0_HOST_LS_SCL")
		)
		(pad "2" smd circle
			(at 0.40005 0 180)
			(size 0 0)
			(layers "F.Cu" "F.Mask" "F.Paste")
			(net "I2C_PEX0_HOST_R_SCL")
		)
	)
)
